# T6G (Grand Teton) — schematic netlist excerpt (pin names and nets, part order shuffled) for the footprints in the layout excerpt that follows; sources: Cadence DE-HDL packaged netlist, KiCad conversion of 04192023_DAF0TMB3IC0_F0TG_MB_C_brd_V02_OCP.brd

R1098  Q_RES  1K 1% EMPTY  pkg 0201LF  page 309 : A = RT_CPU0_P3_ADDR3 ; B = GND
C1579  Q_CAP_DIFFBUS  DIFF BUS_0.22UF 6.3V 20% X6S  pkg C0201  page 65 : \1\ = P5E_CPU0_G3_TX_C_DP<0> ; \2\ = P5E_CPU0_G3_TX_DP<0>
C7501  Q_CAP  0.1UF 10V 10% X7S  pkg C0201  page 322 : A = P1V8_CPU1_RT_1D ; B = GND
R3228  Q_RES  200 1% CHIP  pkg 0402LF  page 137 : A = SMB_OCP_V3_2_3V3AUX_BUF_R_SCL ; B = SMB_OCP_V3_2_3V3AUX_BUF_SCL

(kicad_pcb
	(version 20260206)
	(generator "pcbnew")
	(generator_version "10.0")
	(general
		(thickness 1.6)
		(legacy_teardrops no)
	)
	(paper "A4")
	(title_block
		(title "04192023_DAF0TMB3IC0_F0TG_MB_C_brd_V02_OCP.brd")
		(comment 1 "Grand Teton / footprints 559-562 of 8354")
	)
	(layers
		(0 "F.Cu" signal "TOP")
		(4 "In1.Cu" signal "GND")
		(6 "In2.Cu" signal "IN1")
		(8 "In3.Cu" signal "GND1")
		(10 "In4.Cu" signal "IN2")
		(12 "In5.Cu" signal "GND2")
		(14 "In6.Cu" signal "IN3")
		(16 "In7.Cu" signal "GND3")
		(18 "In8.Cu" signal "VCC")
		(20 "In9.Cu" signal "VCC1")
		(22 "In10.Cu" signal "GND4")
		(24 "In11.Cu" signal "IN4")
		(26 "In12.Cu" signal "GND5")
		(28 "In13.Cu" signal "IN5")
		(30 "In14.Cu" signal "GND6")
		(32 "In15.Cu" signal "IN6")
		(34 "In16.Cu" signal "GND7")
		(2 "B.Cu" signal "BOTTOM")
		(9 "F.Adhes" user "F.Adhesive")
		(11 "B.Adhes" user "B.Adhesive")
		(13 "F.Paste" user "Package Geometry/Pastemask Top")
		(15 "B.Paste" user "Package Geometry/Pastemask Bottom")
		(5 "F.SilkS" user "Ref Des/Silkscreen Top")
		(7 "B.SilkS" user "Ref Des/Silkscreen Bottom")
		(1 "F.Mask" user "Board Geometry/Soldermask Top")
		(3 "B.Mask" user "Board Geometry/Soldermask Bottom")
		(17 "Dwgs.User" user "User.Drawings")
		(19 "Cmts.User" user "User.Comments")
		(21 "Eco1.User" user "User.Eco1")
		(23 "Eco2.User" user "User.Eco2")
		(25 "Edge.Cuts" user "Board Geometry/Outline")
		(27 "Margin" user)
		(31 "F.CrtYd" user "Package Geometry/Place Bound Top")
		(29 "B.CrtYd" user "Package Geometry/Place Bound Bottom")
		(35 "F.Fab" user "Ref Des/Assembly Top")
		(33 "B.Fab" user "Ref Des/Assembly Bottom")
	)
	(footprint ""
		(layer "F.Cu")
		(at 153.486612 -40.04056 180)
		(property "Reference" "R3228"
			(at 0 0 180)
			(layer "F.SilkS")
			(hide yes)
			(effects
				(font
					(size 1.27 1.27)
				)
			)
		)
		(property "Value" ""
			(at 0 0 180)
			(layer "F.Fab")
			(effects
				(font
					(size 1.27 1.27)
				)
			)
		)
		(duplicate_pad_numbers_are_jumpers no)
		(fp_line
			(start 0.7874 0.4064)
			(end -0.7874 0.4064)
			(stroke
				(width 0.1524)
				(type default)
			)
			(layer "F.SilkS")
		)
		(fp_line
			(start 0.7874 -0.4064)
			(end 0.7874 0.4064)
			(stroke
				(width 0.1524)
				(type default)
			)
			(layer "F.SilkS")
		)
		(fp_line
			(start -0.7874 0.4064)
			(end -0.7874 -0.4064)
			(stroke
				(width 0.1524)
				(type default)
			)
			(layer "F.SilkS")
		)
		(fp_line
			(start -0.7874 -0.4064)
			(end 0.7874 -0.4064)
			(stroke
				(width 0.1524)
				(type default)
			)
			(layer "F.SilkS")
		)
		(fp_line
			(start 0.67945 0.3048)
			(end 0.120396 0.3048)
			(stroke
				(width 0.1)
				(type default)
			)
			(layer "F.Fab")
		)
		(fp_line
			(start 0.67945 -0.3048)
			(end 0.67945 0.3048)
			(stroke
				(width 0.1)
				(type default)
			)
			(layer "F.Fab")
		)
		(fp_line
			(start 0.12065 -0.2794)
			(end 0.12065 -0.3048)
			(stroke
				(width 0.1)
				(type default)
			)
			(layer "F.Fab")
		)
		(fp_line
			(start 0.12065 -0.3048)
			(end 0.67945 -0.3048)
			(stroke
				(width 0.1)
				(type default)
			)
			(layer "F.Fab")
		)
		(fp_line
			(start 0.120396 0.3048)
			(end 0.120396 0.2794)
			(stroke
				(width 0.1)
				(type default)
			)
			(layer "F.Fab")
		)
		(fp_line
			(start 0.120396 0.2794)
			(end -0.12065 0.2794)
			(stroke
				(width 0.1)
				(type default)
			)
			(layer "F.Fab")
		)
		(fp_line
			(start -0.12065 0.3048)
			(end -0.67945 0.3048)
			(stroke
				(width 0.1)
				(type default)
			)
			(layer "F.Fab")
		)
		(fp_line
			(start -0.12065 0.2794)
			(end -0.12065 0.3048)
			(stroke
				(width 0.1)
				(type default)
			)
			(layer "F.Fab")
		)
		(fp_line
			(start -0.12065 -0.2794)
			(end 0.12065 -0.2794)
			(stroke
				(width 0.1)
				(type default)
			)
			(layer "F.Fab")
		)
		(fp_line
			(start -0.12065 -0.305054)
			(end -0.12065 -0.2794)
			(stroke
				(width 0.1)
				(type default)
			)
			(layer "F.Fab")
		)
		(fp_line
			(start -0.67945 0.3048)
			(end -0.67945 -0.305054)
			(stroke
				(width 0.1)
				(type default)
			)
			(layer "F.Fab")
		)
		(fp_line
			(start -0.67945 -0.305054)
			(end -0.12065 -0.305054)
			(stroke
				(width 0.1)
				(type default)
			)
			(layer "F.Fab")
		)
		(pad "1" smd circle
			(at -0.40005 0 180)
			(size 0 0)
			(layers "F.Cu" "F.Mask" "F.Paste")
			(net "SMB_OCP_V3_2_3V3AUX_BUF_R_SCL")
		)
		(pad "2" smd circle
			(at 0.40005 0 180)
			(size 0 0)
			(layers "F.Cu" "F.Mask" "F.Paste")
			(net "SMB_OCP_V3_2_3V3AUX_BUF_SCL")
		)
	)
	(footprint ""
		(layer "F.Cu")
		(at 394.981938 -395.1732 90)
		(property "Reference" "R1098"
			(at 0 0 90)
			(layer "F.SilkS")
			(hide yes)
			(effects
				(font
					(size 1.27 1.27)
				)
			)
		)
		(property "Value" ""
			(at 0 0 90)
			(layer "F.Fab")
			(effects
				(font
					(size 1.27 1.27)
				)
			)
		)
		(duplicate_pad_numbers_are_jumpers no)
		(fp_line
			(start 0.32512 -0.175006)
			(end 0.32512 0.175006)
			(stroke
				(width 0.1)
				(type default)
			)
			(layer "F.Fab")
		)
		(fp_line
			(start -0.32512 -0.175006)
			(end 0.32512 -0.175006)
			(stroke
				(width 0.1)
				(type default)
			)
			(layer "F.Fab")
		)
		(fp_line
			(start 0.32512 0.175006)
			(end -0.32512 0.175006)
			(stroke
				(width 0.1)
				(type default)
			)
			(layer "F.Fab")
		)
		(fp_line
			(start -0.32512 0.175006)
			(end -0.32512 -0.175006)
			(stroke
				(width 0.1)
				(type default)
			)
			(layer "F.Fab")
		)
		(pad "1" smd rect
			(at -0.2667 0 90)
			(size 0.3048 0.381)
			(layers "F.Cu" "F.Mask" "F.Paste")
			(net "RT_CPU0_P3_ADDR3")
		)
		(pad "2" smd rect
			(at 0.2667 0 270)
			(size 0.3048 0.381)
			(layers "F.Cu" "F.Mask" "F.Paste")
			(net "GND")
		)
	)
	(footprint ""
		(layer "F.Cu")
		(at 104.741726 -397.13408 180)
		(property "Reference" "C7501"
			(at 0 0 180)
			(layer "F.SilkS")
			(hide yes)
			(effects
				(font
					(size 1.27 1.27)
				)
			)
		)
		(property "Value" ""
			(at 0 0 180)
			(layer "F.Fab")
			(effects
				(font
					(size 1.27 1.27)
				)
			)
		)
		(duplicate_pad_numbers_are_jumpers no)
		(fp_line
			(start 0.299974 0.150114)
			(end -0.299974 0.150114)
			(stroke
				(width 0.1)
				(type default)
			)
			(layer "F.Fab")
		)
		(fp_line
			(start 0.299974 -0.150114)
			(end 0.299974 0.150114)
			(stroke
				(width 0.1)
				(type default)
			)
			(layer "F.Fab")
		)
		(fp_line
			(start -0.299974 0.150114)
			(end -0.299974 -0.150114)
			(stroke
				(width 0.1)
				(type default)
			)
			(layer "F.Fab")
		)
		(fp_line
			(start -0.299974 -0.150114)
			(end 0.299974 -0.150114)
			(stroke
				(width 0.1)
				(type default)
			)
			(layer "F.Fab")
		)
		(pad "1" smd rect
			(at -0.2667 0 180)
			(size 0.3048 0.381)
			(layers "F.Cu" "F.Mask" "F.Paste")
			(net "P1V8_CPU1_RT_1D")
		)
		(pad "2" smd rect
			(at 0.2667 0 180)
			(size 0.3048 0.381)
			(layers "F.Cu" "F.Mask" "F.Paste")
			(net "GND")
		)
	)
	(footprint ""
		(layer "F.Cu")
		(at 433.1716 -17.624298 90)
		(property "Reference" "C1579"
			(at 0 0 90)
			(layer "F.SilkS")
			(hide yes)
			(effects
				(font
					(size 1.27 1.27)
				)
			)
		)
		(property "Value" ""
			(at 0 0 90)
			(layer "F.Fab")
			(effects
				(font
					(size 1.27 1.27)
				)
			)
		)
		(duplicate_pad_numbers_are_jumpers no)
		(fp_line
			(start 0.299974 -0.150114)
			(end 0.299974 0.150114)
			(stroke
				(width 0.1)
				(type default)
			)
			(layer "F.Fab")
		)
		(fp_line
			(start -0.299974 -0.150114)
			(end 0.299974 -0.150114)
			(stroke
				(width 0.1)
				(type default)
			)
			(layer "F.Fab")
		)
		(fp_line
			(start 0.299974 0.150114)
			(end -0.299974 0.150114)
			(stroke
				(width 0.1)
				(type default)
			)
			(layer "F.Fab")
		)
		(fp_line
			(start -0.299974 0.150114)
			(end -0.299974 -0.150114)
			(stroke
				(width 0.1)
				(type default)
			)
			(layer "F.Fab")
		)
		(pad "1" smd rect
			(at -0.2667 0 90)
			(size 0.3048 0.381)
			(layers "F.Cu" "F.Mask" "F.Paste")
			(net "P5E_CPU0_G3_TX_C_DP<0>")
		)
		(pad "2" smd rect
			(at 0.2667 0 90)
			(size 0.3048 0.381)
			(layers "F.Cu" "F.Mask" "F.Paste")
			(net "P5E_CPU0_G3_TX_DP<0>")
		)
	)
)
